FILE_TYPE = CONNECTIVITY;
{Allegro Design Entry HDL 17.4-2019 S026 (4007227) 1/17/2022}
"PAGE_NUMBER" = 24;
0"NC";
1"P5E_CPU0_P1_TX_DP<15:0>";
2"P5E_CPU0_P1_TX_DN<15:0>";
3"P5E_CPU0_P1_RX_DP<15:0>";
4"P5E_CPU0_P1_RX_DN<15:0>";
5"P5E_CPU0_P0_TX_DP<15:0>";
6"P5E_CPU0_P0_RX_DP<15:0>";
7"P5E_CPU0_P0_RX_DN<15:0>";
8"P5E_CPU0_P0_TX_DN<15:0>";
9"P5E_CPU0_P0_TX_DP<11>";
10"P5E_CPU0_P0_TX_DN<0>";
11"P5E_CPU0_P0_TX_DN<9>";
12"P5E_CPU0_P0_TX_DN<8>";
13"P5E_CPU0_P0_TX_DN<7>";
14"P5E_CPU0_P0_TX_DN<6>";
15"P5E_CPU0_P0_TX_DN<5>";
16"P5E_CPU0_P0_TX_DN<3>";
17"P5E_CPU0_P0_TX_DN<11>";
18"P5E_CPU0_P0_TX_DN<14>";
19"P5E_CPU0_P0_TX_DN<10>";
20"P5E_CPU0_P0_TX_DN<1>";
21"P5E_CPU0_P0_TX_DN<4>";
22"P5E_CPU0_P0_TX_DN<15>";
23"P5E_CPU0_P0_TX_DN<13>";
24"P5E_CPU0_P0_TX_DN<2>";
25"P5E_CPU0_P0_TX_DN<12>";
26"P5E_CPU0_P0_TX_DP<14>";
27"P5E_CPU0_P0_RX_DN<8>";
28"P5E_CPU0_P0_RX_DP<9>";
29"P5E_CPU0_P0_TX_DP<15>";
30"P5E_CPU0_P0_TX_DP<12>";
31"P5E_CPU0_P1_TX_DN<5>";
32"P5E_CPU0_P0_TX_DP<3>";
33"P5E_CPU0_P0_TX_DP<4>";
34"P5E_CPU0_P1_TX_DP<2>";
35"P5E_CPU0_P0_TX_DP<2>";
36"P5E_CPU0_P0_RX_DN<0>";
37"P5E_CPU0_P0_RX_DP<1>";
38"P5E_CPU0_P0_RX_DN<1>";
39"P5E_CPU0_P0_RX_DN<14>";
40"P5E_CPU0_P0_RX_DP<0>";
41"P5E_CPU0_P0_RX_DN<3>";
42"P5E_CPU0_P0_RX_DP<3>";
43"P5E_CPU0_P0_RX_DN<2>";
44"P5E_CPU0_P0_RX_DP<2>";
45"P5E_CPU0_P0_RX_DN<15>";
46"P5E_CPU0_P0_RX_DP<15>";
47"P5E_CPU0_P0_RX_DN<13>";
48"P5E_CPU0_P0_RX_DP<12>";
49"P5E_CPU0_P0_RX_DP<10>";
50"P5E_CPU0_P0_RX_DN<6>";
51"P5E_CPU0_P0_RX_DP<7>";
52"P5E_CPU0_P0_RX_DP<4>";
53"P5E_CPU0_P0_RX_DN<4>";
54"P5E_CPU0_P0_RX_DN<7>";
55"P5E_CPU0_P0_RX_DP<5>";
56"P5E_CPU0_P0_RX_DN<5>";
57"P5E_CPU0_P0_RX_DP<6>";
58"P5E_CPU0_P0_RX_DP<14>";
59"P5E_CPU0_P0_RX_DP<8>";
60"P5E_CPU0_P0_RX_DN<12>";
61"P5E_CPU0_P0_RX_DN<10>";
62"P5E_CPU0_P0_RX_DN<9>";
63"P5E_CPU0_P0_RX_DP<13>";
64"P5E_CPU0_P0_RX_DN<11>";
65"P5E_CPU0_P0_RX_DP<11>";
66"P5E_CPU0_P1_TX_DN<6>";
67"P5E_CPU0_P1_TX_DN<7>";
68"P5E_CPU0_P1_TX_DP<5>";
69"P5E_CPU0_P1_TX_DP<7>";
70"P5E_CPU0_P1_TX_DP<6>";
71"P5E_CPU0_P1_TX_DN<8>";
72"P5E_CPU0_P1_TX_DN<9>";
73"P5E_CPU0_P1_TX_DP<10>";
74"P5E_CPU0_P1_TX_DP<9>";
75"P5E_CPU0_P1_TX_DP<8>";
76"P5E_CPU0_P1_TX_DP<11>";
77"P5E_CPU0_P1_TX_DN<13>";
78"P5E_CPU0_P1_TX_DN<15>";
79"P5E_CPU0_P1_TX_DP<14>";
80"P5E_CPU0_P1_TX_DP<15>";
81"P5E_CPU0_P1_RX_DN<13>";
82"P5E_CPU0_P1_RX_DP<15>";
83"P5E_CPU0_P1_RX_DP<2>";
84"P5E_CPU0_P1_RX_DN<2>";
85"P5E_CPU0_P1_RX_DN<1>";
86"P5E_CPU0_P1_RX_DP<3>";
87"P5E_CPU0_P1_RX_DP<4>";
88"P5E_CPU0_P1_RX_DP<5>";
89"P5E_CPU0_P1_RX_DP<6>";
90"P5E_CPU0_P1_RX_DP<7>";
91"P5E_CPU0_P1_RX_DN<6>";
92"P5E_CPU0_P1_RX_DN<7>";
93"P5E_CPU0_P1_RX_DP<8>";
94"P5E_CPU0_P1_RX_DP<9>";
95"P5E_CPU0_P1_RX_DP<10>";
96"P5E_CPU0_P1_RX_DP<11>";
97"P5E_CPU0_P1_RX_DP<13>";
98"P5E_CPU0_P1_RX_DP<12>";
99"P5E_CPU0_P1_RX_DN<8>";
100"P5E_CPU0_P1_RX_DN<9>";
101"P5E_CPU0_P1_RX_DN<10>";
102"P5E_CPU0_P1_RX_DN<11>";
103"P5E_CPU0_P1_RX_DN<12>";
104"P5E_CPU0_P1_RX_DP<14>";
105"P5E_CPU0_P1_RX_DN<15>";
106"P5E_CPU0_P1_RX_DN<14>";
107"P5E_CPU0_P1_RX_DN<3>";
108"P5E_CPU0_P1_RX_DN<4>";
109"P5E_CPU0_P1_RX_DN<5>";
110"P5E_CPU0_P1_TX_DN<3>";
111"P5E_CPU0_P1_TX_DN<4>";
112"P5E_CPU0_P1_TX_DP<4>";
113"P5E_CPU0_P0_TX_DP<13>";
114"P5E_CPU0_P0_TX_DP<7>";
115"P5E_CPU0_P0_TX_DP<6>";
116"P5E_CPU0_P0_TX_DP<5>";
117"P5E_CPU0_P0_TX_DP<8>";
118"P5E_CPU0_P0_TX_DP<9>";
119"P5E_CPU0_P0_TX_DP<10>";
120"P5E_CPU0_P0_TX_DP<0>";
121"P5E_CPU0_P0_TX_DP<1>";
122"P5E_CPU0_P1_RX_DP<0>";
123"P5E_CPU0_P1_RX_DN<0>";
124"P5E_CPU0_P1_RX_DP<1>";
125"P5E_CPU0_P1_TX_DP<0>";
126"P5E_CPU0_P1_TX_DP<1>";
127"P5E_CPU0_P1_TX_DN<0>";
128"P5E_CPU0_P1_TX_DN<14>";
129"P5E_CPU0_P1_TX_DP<13>";
130"P5E_CPU0_P1_TX_DN<12>";
131"P5E_CPU0_P1_TX_DP<12>";
132"P5E_CPU0_P1_TX_DN<11>";
133"P5E_CPU0_P1_TX_DN<10>";
134"P5E_CPU0_P1_TX_DN<2>";
135"P5E_CPU0_P1_TX_DN<1>";
136"P5E_CPU0_P1_TX_DP<3>";
%"GENOA_SP5"
"15","(-4925,5000)","0","pure_quanta","I148";
;
LOCATION"U25"
$SEC"15"
CDS_SEC"15"
VALUE"SOCKET6096_13568-001"
MATERIAL"IO"
PART_TYPE"SMLF"
CDS_LIB"pure_quanta"
NEEDS_NO_SIZE"TRUE"
CDS_LMAN_SYM_OUTLINE"-1100,950,1100,-950"
PART_NUMBER"DGA^6000030";
"P0_RXP11||SATA13_RXP"
$PN"BU43"65;
"P0_TXP12||SATA14_TXP"
$PN"CN44"30;
"P0_TXP15||SATA17_TXP"
$PN"CM41"29;
"P0_RXN11||SATA13_RXN"
$PN"BU44"64;
"P0_RXN14||SATA16_RXN"
$PN"BV41"39;
"P0_TXN15||SATA17_TXN"
$PN"CM40"22;
"P0_RXP13||SATA15_RXP"
$PN"CB40"63;
"P0_TXN9||SATA11_TXN"
$PN"CN46"11;
"P0_TXN12||SATA14_TXN"
$PN"CN43"25;
"P0_RXP10||SATA12_RXP"
$PN"CA43"49;
"P0_RXN9||SATA11_RXN"
$PN"BW44"62;
"P0_TXP11||SATA13_TXP"
$PN"CU44"9;
"P0_TXP14||SATA16_TXP"
$PN"CP41"26;
"P0_RXN10||SATA12_RXN"
$PN"CA44"61;
"P0_RXN13||SATA15_RXN"
$PN"CB41"47;
"P0_TXP9||SATA11_TXP"
$PN"CN47"118;
"P0_RXP9||SATA11_RXP"
$PN"BW43"28;
"P0_TXN14||SATA16_TXN"
$PN"CP40"18;
"P0_RXP12||SATA14_RXP"
$PN"BY40"48;
"P0_RXP15||SATA17_RXP"
$PN"BT40"46;
"P0_TXN8||SATA10_TXN"
$PN"CU46"12;
"P0_TXN11||SATA13_TXN"
$PN"CU43"17;
"P0_RXN8||SATA10_RXN"
$PN"BU47"27;
"P0_TXP13||SATA15_TXP"
$PN"CT41"113;
"P0_TXP10||SATA12_TXP"
$PN"CR44"119;
"P0_RXN15||SATA17_RXN"
$PN"BT41"45;
"P0_TXP8||SATA10_TXP"
$PN"CU47"117;
"P0_RXN12||SATA14_RXN"
$PN"BY41"60;
"P0_RXP8||SATA10_RXP"
$PN"BU46"59;
"P0_RXP14||SATA16_RXP"
$PN"BV40"58;
"P0_TXN10||SATA12_TXN"
$PN"CR43"19;
"P0_TXN13||SATA15_TXN"
$PN"CT40"23;
"P0_TXP3||SATA03_TXP"
$PN"CN50"32;
"P0_TXP6||SATA06_TXP"
$PN"CL50"115;
"P0_TXP0||SATA00_TXP"
$PN"CN53"120;
"P0_RXP3||SATA03_RXP"
$PN"BW49"42;
"P0_RXP6||SATA06_RXP"
$PN"BW46"57;
"P0_TXN5||SATA05_TXN"
$PN"CU49"15;
"P0_RXP0||SATA00_RXP"
$PN"BW52"40;
"P0_TXN2||SATA02_TXN"
$PN"CL52"24;
"P0_RXN2||SATA02_RXN"
$PN"BU53"43;
"P0_RXN5||SATA05_RXN"
$PN"BU50"56;
"P0_TXP2||SATA02_TXP"
$PN"CL53"35;
"P0_TXP5||SATA05_TXP"
$PN"CU50"116;
"P0_RXP5||SATA05_RXP"
$PN"BU49"55;
"P0_RXP2||SATA02_RXP"
$PN"BU52"44;
"P0_TXN1||SATA01_TXN"
$PN"CR52"20;
"P0_TXN7||SATA07_TXN"
$PN"CR46"13;
"P0_TXN4||SATA04_TXN"
$PN"CR49"21;
"P0_RXN7||SATA07_RXN"
$PN"CA47"54;
"P0_RXN1||SATA01_RXN"
$PN"CA53"38;
"P0_RXN4||SATA04_RXN"
$PN"CA50"53;
"P0_TXP7||SATA07_TXP"
$PN"CR47"114;
"P0_TXP1||SATA01_TXP"
$PN"CR53"121;
"P0_TXP4||SATA04_TXP"
$PN"CR50"33;
"P0_RXP4||SATA04_RXP"
$PN"CA49"52;
"P0_RXP7||SATA07_RXP"
$PN"CA46"51;
"P0_TXN6||SATA06_TXN"
$PN"CL49"14;
"P0_RXP1||SATA01_RXP"
$PN"CA52"37;
"P0_TXN0||SATA00_TXN"
$PN"CN52"10;
"P0_TXN3||SATA03_TXN"
$PN"CN49"16;
"P0_RXN3||SATA03_RXN"
$PN"BW50"41;
"P0_RXN6||SATA06_RXN"
$PN"BW47"50;
"P0_RXN0||SATA00_RXN"
$PN"BW53"36;
%"GENOA_SP5"
"16","(-5000,1525)","0","pure_quanta","I149";
;
LOCATION"U25"
$SEC"16"
CDS_SEC"16"
PART_TYPE"SMLF"
MATERIAL"IO"
VALUE"SOCKET6096_13568-001"
CDS_LMAN_SYM_OUTLINE"-1100,950,1100,-950"
NEEDS_NO_SIZE"TRUE"
CDS_LIB"pure_quanta"
PART_NUMBER"DGA^6000030";
"P1_RXN6"
$PN"CE47"91;
"P1_RXN5"
$PN"CC50"109;
"P1_RXP7"
$PN"CG46"90;
"P1_TXN7"
$PN"DA46"67;
"P1_RXN4"
$PN"CG50"108;
"P1_RXP6"
$PN"CE46"89;
"P1_TXN6"
$PN"CW49"66;
"P1_RXN3"
$PN"CE50"107;
"P1_RXP5"
$PN"CC49"88;
"P1_TXN5"
$PN"DC49"31;
"P1_TXP7"
$PN"DA47"69;
"P1_RXN2"
$PN"CC53"84;
"P1_RXP4"
$PN"CG49"87;
"P1_TXN4"
$PN"DA49"111;
"P1_TXP6"
$PN"CW50"70;
"P1_RXN1"
$PN"CG53"85;
"P1_RXP3"
$PN"CE49"86;
"P1_TXN3"
$PN"CW52"110;
"P1_TXP5"
$PN"DC50"68;
"P1_RXN0"
$PN"CE53"123;
"P1_RXP2"
$PN"CC52"83;
"P1_TXN2"
$PN"DC52"134;
"P1_TXP4"
$PN"DA50"112;
"P1_RXP1"
$PN"CG52"124;
"P1_TXN1"
$PN"DA52"135;
"P1_TXP3"
$PN"CW53"136;
"P1_RXP0"
$PN"CE52"122;
"P1_TXN0"
$PN"CU52"127;
"P1_TXP2"
$PN"DC53"34;
"P1_TXP1"
$PN"DA53"126;
"P1_TXP0"
$PN"CU53"125;
"P1_RXN7"
$PN"CG47"92;
"P1_TXN15"
$PN"CV40"78;
"P1_TXP15"
$PN"CV41"80;
"P1_TXN14"
$PN"CY40"128;
"P1_TXP14"
$PN"CY41"79;
"P1_TXN13"
$PN"DB40"77;
"P1_TXP13"
$PN"DB41"129;
"P1_TXN12"
$PN"CW43"130;
"P1_TXP12"
$PN"CW44"131;
"P1_TXN11"
$PN"DC43"132;
"P1_TXP11"
$PN"DC44"76;
"P1_TXN10"
$PN"DA43"133;
"P1_TXP10"
$PN"DA44"73;
"P1_TXN9"
$PN"CW46"72;
"P1_TXP9"
$PN"CW47"74;
"P1_TXN8"
$PN"DC46"71;
"P1_TXP8"
$PN"DC47"75;
"P1_RXN15"
$PN"CD41"105;
"P1_RXP15"
$PN"CD40"82;
"P1_RXN14"
$PN"CF41"106;
"P1_RXP14"
$PN"CF40"104;
"P1_RXN13"
$PN"CH41"81;
"P1_RXP13"
$PN"CH40"97;
"P1_RXN12"
$PN"CC44"103;
"P1_RXP12"
$PN"CC43"98;
"P1_RXN11"
$PN"CJ44"102;
"P1_RXP11"
$PN"CJ43"96;
"P1_RXN10"
$PN"CG44"101;
"P1_RXP10"
$PN"CG43"95;
"P1_RXN9"
$PN"CE44"100;
"P1_RXP9"
$PN"CE43"94;
"P1_RXN8"
$PN"CC47"99;
"P1_RXP8"
$PN"CC46"93;
%"TAP"
"6","(-3175,2275)","2","mstr_standard","I220";
;
ROOM"RISER1"
CDS_LIB"mstr_standard"
BOM_COST"IO_SLOT"
BODY_TYPE"PLUMBING"
HDL_TAP"TRUE";
"B \NAC \NWC"2;
"S \NAC"
BN"0"127;
%"TAP"
"6","(-3175,2175)","2","mstr_standard","I221";
;
ROOM"RISER1"
BOM_COST"IO_SLOT"
CDS_LIB"mstr_standard"
BODY_TYPE"PLUMBING"
HDL_TAP"TRUE";
"B \NAC \NWC"2;
"S \NAC"
BN"1"135;
%"TAP"
"6","(-3325,2225)","2","mstr_standard","I222";
;
ROOM"RISER1"
BOM_COST"IO_SLOT"
CDS_LIB"mstr_standard"
BODY_TYPE"PLUMBING"
HDL_TAP"TRUE";
"B \NAC \NWC"1;
"S \NAC"
BN"1"126;
%"TAP"
"6","(-3325,2325)","2","mstr_standard","I223";
;
ROOM"RISER1"
BOM_COST"IO_SLOT"
CDS_LIB"mstr_standard"
BODY_TYPE"PLUMBING"
HDL_TAP"TRUE";
"B \NAC \NWC"1;
"S \NAC"
BN"0"125;
%"TAP"
"6","(-3325,2125)","2","standard","I224";
;
ROOM"RISER1"
BOM_COST"IO_SLOT"
CDS_LIB"standard"
BODY_TYPE"PLUMBING"
HDL_TAP"TRUE";
"B \NAC \NWC"1;
"S \NAC"
BN"2"34;
%"TAP"
"6","(-3175,2075)","2","standard","I225";
;
ROOM"RISER1"
BOM_COST"IO_SLOT"
CDS_LIB"standard"
BODY_TYPE"PLUMBING"
HDL_TAP"TRUE";
"B \NAC \NWC"2;
"S \NAC"
BN"2"134;
%"TAP"
"6","(-3175,1875)","2","standard","I226";
;
ROOM"RISER1"
BOM_COST"IO_SLOT"
CDS_LIB"standard"
BODY_TYPE"PLUMBING"
HDL_TAP"TRUE";
"B \NAC \NWC"2;
"S \NAC"
BN"4"111;
%"TAP"
"6","(-3175,1975)","2","standard","I227";
;
ROOM"RISER1"
BOM_COST"IO_SLOT"
CDS_LIB"standard"
BODY_TYPE"PLUMBING"
HDL_TAP"TRUE";
"B \NAC \NWC"2;
"S \NAC"
BN"3"110;
%"TAP"
"6","(-3325,2025)","2","standard","I228";
;
ROOM"RISER1"
BOM_COST"IO_SLOT"
CDS_LIB"standard"
BODY_TYPE"PLUMBING"
HDL_TAP"TRUE";
"B \NAC \NWC"1;
"S \NAC"
BN"3"136;
%"TAP"
"6","(-3325,1925)","2","standard","I229";
;
ROOM"RISER1"
BOM_COST"IO_SLOT"
CDS_LIB"standard"
BODY_TYPE"PLUMBING"
HDL_TAP"TRUE";
"B \NAC \NWC"1;
"S \NAC"
BN"4"112;
%"TAP"
"6","(-3175,1775)","2","standard","I230";
;
ROOM"RISER1"
BOM_COST"IO_SLOT"
CDS_LIB"standard"
BODY_TYPE"PLUMBING"
HDL_TAP"TRUE";
"B \NAC \NWC"2;
"S \NAC"
BN"5"31;
%"TAP"
"6","(-3175,1675)","2","standard","I231";
;
ROOM"RISER1"
BOM_COST"IO_SLOT"
CDS_LIB"standard"
BODY_TYPE"PLUMBING"
HDL_TAP"TRUE";
"B \NAC \NWC"2;
"S \NAC"
BN"6"66;
%"TAP"
"6","(-3325,1725)","2","standard","I232";
;
ROOM"RISER1"
BOM_COST"IO_SLOT"
CDS_LIB"standard"
BODY_TYPE"PLUMBING"
HDL_TAP"TRUE";
"B \NAC \NWC"1;
"S \NAC"
BN"6"70;
%"TAP"
"6","(-3325,1825)","2","standard","I233";
;
ROOM"RISER1"
BOM_COST"IO_SLOT"
CDS_LIB"standard"
BODY_TYPE"PLUMBING"
HDL_TAP"TRUE";
"B \NAC \NWC"1;
"S \NAC"
BN"5"68;
%"TAP"
"6","(-3325,1625)","2","standard","I234";
;
ROOM"RISER1"
BOM_COST"IO_SLOT"
CDS_LIB"standard"
BODY_TYPE"PLUMBING"
HDL_TAP"TRUE";
"B \NAC \NWC"1;
"S \NAC"
BN"7"69;
%"TAP"
"6","(-3175,1575)","2","standard","I235";
;
ROOM"RISER1"
BOM_COST"IO_SLOT"
CDS_LIB"standard"
BODY_TYPE"PLUMBING"
HDL_TAP"TRUE";
"B \NAC \NWC"2;
"S \NAC"
BN"7"67;
%"TAP"
"6","(-3175,1375)","2","standard","I236";
;
ROOM"RISER1"
BOM_COST"IO_SLOT"
CDS_LIB"standard"
BODY_TYPE"PLUMBING"
HDL_TAP"TRUE";
"B \NAC \NWC"2;
"S \NAC"
BN"9"72;
%"TAP"
"6","(-3175,1475)","2","standard","I237";
;
ROOM"RISER1"
BOM_COST"IO_SLOT"
CDS_LIB"standard"
BODY_TYPE"PLUMBING"
HDL_TAP"TRUE";
"B \NAC \NWC"2;
"S \NAC"
BN"8"71;
%"TAP"
"6","(-3325,1525)","2","standard","I238";
;
ROOM"RISER1"
BOM_COST"IO_SLOT"
CDS_LIB"standard"
BODY_TYPE"PLUMBING"
HDL_TAP"TRUE";
"B \NAC \NWC"1;
"S \NAC"
BN"8"75;
%"TAP"
"6","(-3325,1425)","2","standard","I239";
;
ROOM"RISER1"
BOM_COST"IO_SLOT"
CDS_LIB"standard"
BODY_TYPE"PLUMBING"
HDL_TAP"TRUE";
"B \NAC \NWC"1;
"S \NAC"
BN"9"74;
%"TAP"
"6","(-3175,1275)","2","standard","I240";
;
ROOM"RISER1"
BOM_COST"IO_SLOT"
CDS_LIB"standard"
BODY_TYPE"PLUMBING"
HDL_TAP"TRUE";
"B \NAC \NWC"2;
"S \NAC"
BN"10"133;
%"TAP"
"6","(-3175,1175)","2","standard","I241";
;
ROOM"RISER1"
BOM_COST"IO_SLOT"
CDS_LIB"standard"
BODY_TYPE"PLUMBING"
HDL_TAP"TRUE";
"B \NAC \NWC"2;
"S \NAC"
BN"11"132;
%"TAP"
"6","(-3325,1125)","2","standard","I242";
;
ROOM"RISER1"
BOM_COST"IO_SLOT"
CDS_LIB"standard"
BODY_TYPE"PLUMBING"
HDL_TAP"TRUE";
"B \NAC \NWC"1;
"S \NAC"
BN"12"131;
%"TAP"
"6","(-3325,1225)","2","standard","I243";
;
ROOM"RISER1"
BOM_COST"IO_SLOT"
CDS_LIB"standard"
BODY_TYPE"PLUMBING"
HDL_TAP"TRUE";
"B \NAC \NWC"1;
"S \NAC"
BN"11"76;
%"TAP"
"6","(-3325,1325)","2","standard","I244";
;
ROOM"RISER1"
BOM_COST"IO_SLOT"
CDS_LIB"standard"
BODY_TYPE"PLUMBING"
HDL_TAP"TRUE";
"B \NAC \NWC"1;
"S \NAC"
BN"10"73;
%"TAP"
"6","(-3175,975)","2","standard","I245";
;
ROOM"RISER1"
BOM_COST"IO_SLOT"
CDS_LIB"standard"
BODY_TYPE"PLUMBING"
HDL_TAP"TRUE";
"B \NAC \NWC"2;
"S \NAC"
BN"13"77;
%"TAP"
"6","(-3175,1075)","2","standard","I246";
;
ROOM"RISER1"
BOM_COST"IO_SLOT"
CDS_LIB"standard"
BODY_TYPE"PLUMBING"
HDL_TAP"TRUE";
"B \NAC \NWC"2;
"S \NAC"
BN"12"130;
%"TAP"
"6","(-3175,875)","2","standard","I247";
;
ROOM"RISER1"
BOM_COST"IO_SLOT"
CDS_LIB"standard"
BODY_TYPE"PLUMBING"
HDL_TAP"TRUE";
"B \NAC \NWC"2;
"S \NAC"
BN"14"128;
%"TAP"
"6","(-3325,1025)","2","standard","I248";
;
ROOM"RISER1"
BOM_COST"IO_SLOT"
CDS_LIB"standard"
BODY_TYPE"PLUMBING"
HDL_TAP"TRUE";
"B \NAC \NWC"1;
"S \NAC"
BN"13"129;
%"TAP"
"6","(-3325,925)","2","standard","I249";
;
ROOM"RISER1"
BOM_COST"IO_SLOT"
CDS_LIB"standard"
BODY_TYPE"PLUMBING"
HDL_TAP"TRUE";
"B \NAC \NWC"1;
"S \NAC"
BN"14"79;
%"TAP"
"6","(-3325,825)","2","standard","I250";
;
ROOM"RISER1"
BOM_COST"IO_SLOT"
CDS_LIB"standard"
BODY_TYPE"PLUMBING"
HDL_TAP"TRUE";
"B \NAC \NWC"1;
"S \NAC"
BN"15"80;
%"TAP"
"6","(-3175,775)","2","standard","I251";
;
ROOM"RISER1"
BOM_COST"IO_SLOT"
CDS_LIB"standard"
BODY_TYPE"PLUMBING"
HDL_TAP"TRUE";
"B \NAC \NWC"2;
"S \NAC"
BN"15"78;
%"TAP"
"6","(-6900,775)","0","standard","I292";
;
CDS_LIB"standard"
BODY_TYPE"PLUMBING"
HDL_TAP"TRUE";
"B \NAC \NWC"4;
"S \NAC"
BN"15"105;
%"TAP"
"6","(-6900,875)","0","standard","I293";
;
CDS_LIB"standard"
BODY_TYPE"PLUMBING"
HDL_TAP"TRUE";
"B \NAC \NWC"4;
"S \NAC"
BN"14"106;
%"TAP"
"6","(-6750,825)","0","standard","I294";
;
CDS_LIB"standard"
BODY_TYPE"PLUMBING"
HDL_TAP"TRUE";
"B \NAC \NWC"3;
"S \NAC"
BN"15"82;
%"TAP"
"6","(-6750,925)","0","standard","I295";
;
CDS_LIB"standard"
BODY_TYPE"PLUMBING"
HDL_TAP"TRUE";
"B \NAC \NWC"3;
"S \NAC"
BN"14"104;
%"TAP"
"6","(-6900,1075)","0","standard","I296";
;
CDS_LIB"standard"
BODY_TYPE"PLUMBING"
HDL_TAP"TRUE";
"B \NAC \NWC"4;
"S \NAC"
BN"12"103;
%"TAP"
"6","(-6900,975)","0","standard","I297";
;
CDS_LIB"standard"
BODY_TYPE"PLUMBING"
HDL_TAP"TRUE";
"B \NAC \NWC"4;
"S \NAC"
BN"13"81;
%"TAP"
"6","(-6900,1175)","0","standard","I298";
;
CDS_LIB"standard"
BODY_TYPE"PLUMBING"
HDL_TAP"TRUE";
"B \NAC \NWC"4;
"S \NAC"
BN"11"102;
%"TAP"
"6","(-6750,1025)","0","standard","I299";
;
CDS_LIB"standard"
BODY_TYPE"PLUMBING"
HDL_TAP"TRUE";
"B \NAC \NWC"3;
"S \NAC"
BN"13"97;
%"TAP"
"6","(-6750,1125)","0","standard","I300";
;
CDS_LIB"standard"
BODY_TYPE"PLUMBING"
HDL_TAP"TRUE";
"B \NAC \NWC"3;
"S \NAC"
BN"12"98;
%"TAP"
"6","(-6900,1275)","0","standard","I301";
;
CDS_LIB"standard"
BODY_TYPE"PLUMBING"
HDL_TAP"TRUE";
"B \NAC \NWC"4;
"S \NAC"
BN"10"101;
%"TAP"
"6","(-6900,1375)","0","standard","I302";
;
CDS_LIB"standard"
BODY_TYPE"PLUMBING"
HDL_TAP"TRUE";
"B \NAC \NWC"4;
"S \NAC"
BN"9"100;
%"TAP"
"6","(-6750,1225)","0","standard","I303";
;
CDS_LIB"standard"
BODY_TYPE"PLUMBING"
HDL_TAP"TRUE";
"B \NAC \NWC"3;
"S \NAC"
BN"11"96;
%"TAP"
"6","(-6750,1325)","0","standard","I304";
;
CDS_LIB"standard"
BODY_TYPE"PLUMBING"
HDL_TAP"TRUE";
"B \NAC \NWC"3;
"S \NAC"
BN"10"95;
%"TAP"
"6","(-6750,1425)","0","standard","I305";
;
CDS_LIB"standard"
BODY_TYPE"PLUMBING"
HDL_TAP"TRUE";
"B \NAC \NWC"3;
"S \NAC"
BN"9"94;
%"TAP"
"6","(-6900,1575)","0","standard","I308";
;
CDS_LIB"standard"
BODY_TYPE"PLUMBING"
HDL_TAP"TRUE";
"B \NAC \NWC"4;
"S \NAC"
BN"7"92;
%"TAP"
"6","(-6900,1475)","0","standard","I309";
;
CDS_LIB"standard"
BODY_TYPE"PLUMBING"
HDL_TAP"TRUE";
"B \NAC \NWC"4;
"S \NAC"
BN"8"99;
%"TAP"
"6","(-6900,1675)","0","standard","I310";
;
CDS_LIB"standard"
BODY_TYPE"PLUMBING"
HDL_TAP"TRUE";
"B \NAC \NWC"4;
"S \NAC"
BN"6"91;
%"TAP"
"6","(-6750,1525)","0","standard","I311";
;
CDS_LIB"standard"
BODY_TYPE"PLUMBING"
HDL_TAP"TRUE";
"B \NAC \NWC"3;
"S \NAC"
BN"8"93;
%"TAP"
"6","(-6750,1625)","0","standard","I312";
;
CDS_LIB"standard"
BODY_TYPE"PLUMBING"
HDL_TAP"TRUE";
"B \NAC \NWC"3;
"S \NAC"
BN"7"90;
%"TAP"
"6","(-6750,1725)","0","standard","I313";
;
CDS_LIB"standard"
BODY_TYPE"PLUMBING"
HDL_TAP"TRUE";
"B \NAC \NWC"3;
"S \NAC"
BN"6"89;
%"TAP"
"6","(-6900,1775)","0","standard","I314";
;
CDS_LIB"standard"
BODY_TYPE"PLUMBING"
HDL_TAP"TRUE";
"B \NAC \NWC"4;
"S \NAC"
BN"5"109;
%"TAP"
"6","(-6900,1975)","0","standard","I315";
;
CDS_LIB"standard"
BODY_TYPE"PLUMBING"
HDL_TAP"TRUE";
"B \NAC \NWC"4;
"S \NAC"
BN"3"107;
%"TAP"
"6","(-6900,1875)","0","standard","I316";
;
CDS_LIB"standard"
BODY_TYPE"PLUMBING"
HDL_TAP"TRUE";
"B \NAC \NWC"4;
"S \NAC"
BN"4"108;
%"TAP"
"6","(-6750,1825)","0","standard","I317";
;
CDS_LIB"standard"
BODY_TYPE"PLUMBING"
HDL_TAP"TRUE";
"B \NAC \NWC"3;
"S \NAC"
BN"5"88;
%"TAP"
"6","(-6750,1925)","0","standard","I318";
;
CDS_LIB"standard"
BODY_TYPE"PLUMBING"
HDL_TAP"TRUE";
"B \NAC \NWC"3;
"S \NAC"
BN"4"87;
%"TAP"
"6","(-6900,2075)","0","standard","I319";
;
CDS_LIB"standard"
BODY_TYPE"PLUMBING"
HDL_TAP"TRUE";
"B \NAC \NWC"4;
"S \NAC"
BN"2"84;
%"TAP"
"6","(-6900,2175)","0","mstr_standard","I320";
;
CDS_LIB"mstr_standard"
BODY_TYPE"PLUMBING"
HDL_TAP"TRUE";
"B \NAC \NWC"4;
"S \NAC"
BN"1"85;
%"TAP"
"6","(-6750,2025)","0","standard","I321";
;
CDS_LIB"standard"
BODY_TYPE"PLUMBING"
HDL_TAP"TRUE";
"B \NAC \NWC"3;
"S \NAC"
BN"3"86;
%"TAP"
"6","(-6750,2125)","0","mstr_standard","I322";
;
CDS_LIB"mstr_standard"
BODY_TYPE"PLUMBING"
HDL_TAP"TRUE";
"B \NAC \NWC"3;
"S \NAC"
BN"2"83;
%"TAP"
"6","(-6750,2225)","0","mstr_standard","I323";
;
CDS_LIB"mstr_standard"
BODY_TYPE"PLUMBING"
HDL_TAP"TRUE";
"B \NAC \NWC"3;
"S \NAC"
BN"1"124;
%"TAP"
"6","(-6900,2275)","0","mstr_standard","I324";
;
CDS_LIB"mstr_standard"
BODY_TYPE"PLUMBING"
HDL_TAP"TRUE";
"B \NAC \NWC"4;
"S \NAC"
BN"0"123;
%"TAP"
"6","(-6750,2325)","0","mstr_standard","I325";
;
CDS_LIB"mstr_standard"
BODY_TYPE"PLUMBING"
HDL_TAP"TRUE";
"B \NAC \NWC"3;
"S \NAC"
BN"0"122;
%"TAP"
"6","(-6825,4450)","0","standard","I326";
;
CDS_LIB"standard"
BODY_TYPE"PLUMBING"
HDL_TAP"TRUE";
"B \NAC \NWC"7;
"S \NAC"
BN"13"47;
%"TAP"
"6","(-6675,4300)","0","standard","I327";
;
CDS_LIB"standard"
BODY_TYPE"PLUMBING"
HDL_TAP"TRUE";
"B \NAC \NWC"6;
"S \NAC"
BN"15"46;
%"TAP"
"6","(-6675,5800)","0","mstr_standard","I328";
;
CDS_LIB"mstr_standard"
BODY_TYPE"PLUMBING"
HDL_TAP"TRUE";
"B \NAC \NWC"6;
"S \NAC"
BN"0"40;
%"TAP"
"6","(-6675,5700)","0","mstr_standard","I329";
;
CDS_LIB"mstr_standard"
BODY_TYPE"PLUMBING"
HDL_TAP"TRUE";
"B \NAC \NWC"6;
"S \NAC"
BN"1"37;
%"TAP"
"6","(-6675,5600)","0","mstr_standard","I330";
;
CDS_LIB"mstr_standard"
BODY_TYPE"PLUMBING"
HDL_TAP"TRUE";
"B \NAC \NWC"6;
"S \NAC"
BN"2"44;
%"TAP"
"6","(-6825,5550)","0","standard","I331";
;
CDS_LIB"standard"
BODY_TYPE"PLUMBING"
HDL_TAP"TRUE";
"B \NAC \NWC"7;
"S \NAC"
BN"2"43;
%"TAP"
"6","(-6825,5650)","0","mstr_standard","I332";
;
CDS_LIB"mstr_standard"
BODY_TYPE"PLUMBING"
HDL_TAP"TRUE";
"B \NAC \NWC"7;
"S \NAC"
BN"1"38;
%"TAP"
"6","(-6825,5750)","0","mstr_standard","I333";
;
CDS_LIB"mstr_standard"
BODY_TYPE"PLUMBING"
HDL_TAP"TRUE";
"B \NAC \NWC"7;
"S \NAC"
BN"0"36;
%"TAP"
"6","(-6675,5500)","0","standard","I334";
;
CDS_LIB"standard"
BODY_TYPE"PLUMBING"
HDL_TAP"TRUE";
"B \NAC \NWC"6;
"S \NAC"
BN"3"42;
%"TAP"
"6","(-6675,5400)","0","standard","I335";
;
CDS_LIB"standard"
BODY_TYPE"PLUMBING"
HDL_TAP"TRUE";
"B \NAC \NWC"6;
"S \NAC"
BN"4"52;
%"TAP"
"6","(-6675,5300)","0","standard","I336";
;
CDS_LIB"standard"
BODY_TYPE"PLUMBING"
HDL_TAP"TRUE";
"B \NAC \NWC"6;
"S \NAC"
BN"5"55;
%"TAP"
"6","(-6675,5200)","0","standard","I337";
;
CDS_LIB"standard"
BODY_TYPE"PLUMBING"
HDL_TAP"TRUE";
"B \NAC \NWC"6;
"S \NAC"
BN"6"57;
%"TAP"
"6","(-6675,5100)","0","standard","I338";
;
CDS_LIB"standard"
BODY_TYPE"PLUMBING"
HDL_TAP"TRUE";
"B \NAC \NWC"6;
"S \NAC"
BN"7"51;
%"TAP"
"6","(-6825,5350)","0","standard","I339";
;
CDS_LIB"standard"
BODY_TYPE"PLUMBING"
HDL_TAP"TRUE";
"B \NAC \NWC"7;
"S \NAC"
BN"4"53;
%"TAP"
"6","(-6825,5450)","0","standard","I340";
;
CDS_LIB"standard"
BODY_TYPE"PLUMBING"
HDL_TAP"TRUE";
"B \NAC \NWC"7;
"S \NAC"
BN"3"41;
%"TAP"
"6","(-6825,5250)","0","standard","I341";
;
CDS_LIB"standard"
BODY_TYPE"PLUMBING"
HDL_TAP"TRUE";
"B \NAC \NWC"7;
"S \NAC"
BN"5"56;
%"TAP"
"6","(-6825,5150)","0","standard","I342";
;
CDS_LIB"standard"
BODY_TYPE"PLUMBING"
HDL_TAP"TRUE";
"B \NAC \NWC"7;
"S \NAC"
BN"6"50;
%"TAP"
"6","(-6825,5050)","0","standard","I343";
;
CDS_LIB"standard"
BODY_TYPE"PLUMBING"
HDL_TAP"TRUE";
"B \NAC \NWC"7;
"S \NAC"
BN"7"54;
%"TAP"
"6","(-6675,5000)","0","standard","I344";
;
CDS_LIB"standard"
BODY_TYPE"PLUMBING"
HDL_TAP"TRUE";
"B \NAC \NWC"6;
"S \NAC"
BN"8"59;
%"TAP"
"6","(-6675,4900)","0","standard","I345";
;
CDS_LIB"standard"
BODY_TYPE"PLUMBING"
HDL_TAP"TRUE";
"B \NAC \NWC"6;
"S \NAC"
BN"9"28;
%"TAP"
"6","(-6675,4800)","0","standard","I346";
;
CDS_LIB"standard"
BODY_TYPE"PLUMBING"
HDL_TAP"TRUE";
"B \NAC \NWC"6;
"S \NAC"
BN"10"49;
%"TAP"
"6","(-6675,4700)","0","standard","I347";
;
CDS_LIB"standard"
BODY_TYPE"PLUMBING"
HDL_TAP"TRUE";
"B \NAC \NWC"6;
"S \NAC"
BN"11"65;
%"TAP"
"6","(-6675,4500)","0","standard","I348";
;
CDS_LIB"standard"
BODY_TYPE"PLUMBING"
HDL_TAP"TRUE";
"B \NAC \NWC"6;
"S \NAC"
BN"13"63;
%"TAP"
"6","(-6675,4600)","0","standard","I349";
;
CDS_LIB"standard"
BODY_TYPE"PLUMBING"
HDL_TAP"TRUE";
"B \NAC \NWC"6;
"S \NAC"
BN"12"48;
%"TAP"
"6","(-6825,4950)","0","standard","I350";
;
CDS_LIB"standard"
BODY_TYPE"PLUMBING"
HDL_TAP"TRUE";
"B \NAC \NWC"7;
"S \NAC"
BN"8"27;
%"TAP"
"6","(-6825,4850)","0","standard","I351";
;
CDS_LIB"standard"
BODY_TYPE"PLUMBING"
HDL_TAP"TRUE";
"B \NAC \NWC"7;
"S \NAC"
BN"9"62;
%"TAP"
"6","(-6825,4750)","0","standard","I352";
;
CDS_LIB"standard"
BODY_TYPE"PLUMBING"
HDL_TAP"TRUE";
"B \NAC \NWC"7;
"S \NAC"
BN"10"61;
%"TAP"
"6","(-6825,4650)","0","standard","I353";
;
CDS_LIB"standard"
BODY_TYPE"PLUMBING"
HDL_TAP"TRUE";
"B \NAC \NWC"7;
"S \NAC"
BN"11"64;
%"TAP"
"6","(-6825,4550)","0","standard","I354";
;
CDS_LIB"standard"
BODY_TYPE"PLUMBING"
HDL_TAP"TRUE";
"B \NAC \NWC"7;
"S \NAC"
BN"12"60;
%"TAP"
"6","(-6675,4400)","0","standard","I355";
;
CDS_LIB"standard"
BODY_TYPE"PLUMBING"
HDL_TAP"TRUE";
"B \NAC \NWC"6;
"S \NAC"
BN"14"58;
%"TAP"
"6","(-6825,4250)","0","standard","I356";
;
CDS_LIB"standard"
BODY_TYPE"PLUMBING"
HDL_TAP"TRUE";
"B \NAC \NWC"7;
"S \NAC"
BN"15"45;
%"TAP"
"6","(-6825,4350)","0","standard","I357";
;
CDS_LIB"standard"
BODY_TYPE"PLUMBING"
HDL_TAP"TRUE";
"B \NAC \NWC"7;
"S \NAC"
BN"14"39;
%"TAP"
"6","(-3100,5750)","2","mstr_standard","I360";
;
ROOM"RISER1"
BOM_COST"IO_SLOT"
CDS_LIB"mstr_standard"
BODY_TYPE"PLUMBING"
HDL_TAP"TRUE";
"B \NAC \NWC"8;
"S \NAC"
BN"0"10;
%"TAP"
"6","(-3100,5650)","2","mstr_standard","I361";
;
ROOM"RISER1"
BOM_COST"IO_SLOT"
CDS_LIB"mstr_standard"
BODY_TYPE"PLUMBING"
HDL_TAP"TRUE";
"B \NAC \NWC"8;
"S \NAC"
BN"1"20;
%"TAP"
"6","(-3100,5550)","2","standard","I362";
;
ROOM"RISER1"
BOM_COST"IO_SLOT"
CDS_LIB"standard"
BODY_TYPE"PLUMBING"
HDL_TAP"TRUE";
"B \NAC \NWC"8;
"S \NAC"
BN"2"24;
%"TAP"
"6","(-3250,5700)","2","mstr_standard","I363";
;
ROOM"RISER1"
BOM_COST"IO_SLOT"
CDS_LIB"mstr_standard"
BODY_TYPE"PLUMBING"
HDL_TAP"TRUE";
"B \NAC \NWC"5;
"S \NAC"
BN"1"121;
%"TAP"
"6","(-3250,5800)","2","mstr_standard","I364";
;
ROOM"RISER1"
BOM_COST"IO_SLOT"
CDS_LIB"mstr_standard"
BODY_TYPE"PLUMBING"
HDL_TAP"TRUE";
"B \NAC \NWC"5;
"S \NAC"
BN"0"120;
%"TAP"
"6","(-3250,5600)","2","standard","I365";
;
ROOM"RISER1"
BOM_COST"IO_SLOT"
CDS_LIB"standard"
BODY_TYPE"PLUMBING"
HDL_TAP"TRUE";
"B \NAC \NWC"5;
"S \NAC"
BN"2"35;
%"TAP"
"6","(-3100,5450)","2","standard","I366";
;
ROOM"RISER1"
BOM_COST"IO_SLOT"
CDS_LIB"standard"
BODY_TYPE"PLUMBING"
HDL_TAP"TRUE";
"B \NAC \NWC"8;
"S \NAC"
BN"3"16;
%"TAP"
"6","(-3100,5350)","2","standard","I367";
;
ROOM"RISER1"
BOM_COST"IO_SLOT"
CDS_LIB"standard"
BODY_TYPE"PLUMBING"
HDL_TAP"TRUE";
"B \NAC \NWC"8;
"S \NAC"
BN"4"21;
%"TAP"
"6","(-3100,5150)","2","standard","I368";
;
ROOM"RISER1"
BOM_COST"IO_SLOT"
CDS_LIB"standard"
BODY_TYPE"PLUMBING"
HDL_TAP"TRUE";
"B \NAC \NWC"8;
"S \NAC"
BN"6"14;
%"TAP"
"6","(-3100,5250)","2","standard","I369";
;
ROOM"RISER1"
BOM_COST"IO_SLOT"
CDS_LIB"standard"
BODY_TYPE"PLUMBING"
HDL_TAP"TRUE";
"B \NAC \NWC"8;
"S \NAC"
BN"5"15;
%"TAP"
"6","(-3100,5050)","2","standard","I370";
;
ROOM"RISER1"
BOM_COST"IO_SLOT"
CDS_LIB"standard"
BODY_TYPE"PLUMBING"
HDL_TAP"TRUE";
"B \NAC \NWC"8;
"S \NAC"
BN"7"13;
%"TAP"
"6","(-3250,5300)","2","standard","I371";
;
ROOM"RISER1"
BOM_COST"IO_SLOT"
CDS_LIB"standard"
BODY_TYPE"PLUMBING"
HDL_TAP"TRUE";
"B \NAC \NWC"5;
"S \NAC"
BN"5"116;
%"TAP"
"6","(-3250,5400)","2","standard","I372";
;
ROOM"RISER1"
BOM_COST"IO_SLOT"
CDS_LIB"standard"
BODY_TYPE"PLUMBING"
HDL_TAP"TRUE";
"B \NAC \NWC"5;
"S \NAC"
BN"4"33;
%"TAP"
"6","(-3250,5500)","2","standard","I373";
;
ROOM"RISER1"
BOM_COST"IO_SLOT"
CDS_LIB"standard"
BODY_TYPE"PLUMBING"
HDL_TAP"TRUE";
"B \NAC \NWC"5;
"S \NAC"
BN"3"32;
%"TAP"
"6","(-3250,5100)","2","standard","I374";
;
ROOM"RISER1"
BOM_COST"IO_SLOT"
CDS_LIB"standard"
BODY_TYPE"PLUMBING"
HDL_TAP"TRUE";
"B \NAC \NWC"5;
"S \NAC"
BN"7"114;
%"TAP"
"6","(-3250,5200)","2","standard","I375";
;
ROOM"RISER1"
BOM_COST"IO_SLOT"
CDS_LIB"standard"
BODY_TYPE"PLUMBING"
HDL_TAP"TRUE";
"B \NAC \NWC"5;
"S \NAC"
BN"6"115;
%"TAP"
"6","(-3100,4950)","2","standard","I376";
;
ROOM"RISER1"
BOM_COST"IO_SLOT"
CDS_LIB"standard"
BODY_TYPE"PLUMBING"
HDL_TAP"TRUE";
"B \NAC \NWC"8;
"S \NAC"
BN"8"12;
%"TAP"
"6","(-3100,4850)","2","standard","I377";
;
ROOM"RISER1"
BOM_COST"IO_SLOT"
CDS_LIB"standard"
BODY_TYPE"PLUMBING"
HDL_TAP"TRUE";
"B \NAC \NWC"8;
"S \NAC"
BN"9"11;
%"TAP"
"6","(-3100,4650)","2","standard","I378";
;
ROOM"RISER1"
BOM_COST"IO_SLOT"
CDS_LIB"standard"
BODY_TYPE"PLUMBING"
HDL_TAP"TRUE";
"B \NAC \NWC"8;
"S \NAC"
BN"11"17;
%"TAP"
"6","(-3100,4750)","2","standard","I379";
;
ROOM"RISER1"
BOM_COST"IO_SLOT"
CDS_LIB"standard"
BODY_TYPE"PLUMBING"
HDL_TAP"TRUE";
"B \NAC \NWC"8;
"S \NAC"
BN"10"19;
%"TAP"
"6","(-3100,4550)","2","standard","I380";
;
ROOM"RISER1"
BOM_COST"IO_SLOT"
CDS_LIB"standard"
BODY_TYPE"PLUMBING"
HDL_TAP"TRUE";
"B \NAC \NWC"8;
"S \NAC"
BN"12"25;
%"TAP"
"6","(-3250,4800)","2","standard","I381";
;
ROOM"RISER1"
BOM_COST"IO_SLOT"
CDS_LIB"standard"
BODY_TYPE"PLUMBING"
HDL_TAP"TRUE";
"B \NAC \NWC"5;
"S \NAC"
BN"10"119;
%"TAP"
"6","(-3250,4900)","2","standard","I382";
;
ROOM"RISER1"
BOM_COST"IO_SLOT"
CDS_LIB"standard"
BODY_TYPE"PLUMBING"
HDL_TAP"TRUE";
"B \NAC \NWC"5;
"S \NAC"
BN"9"118;
%"TAP"
"6","(-3250,5000)","2","standard","I383";
;
ROOM"RISER1"
BOM_COST"IO_SLOT"
CDS_LIB"standard"
BODY_TYPE"PLUMBING"
HDL_TAP"TRUE";
"B \NAC \NWC"5;
"S \NAC"
BN"8"117;
%"TAP"
"6","(-3250,4500)","2","standard","I384";
;
ROOM"RISER1"
BOM_COST"IO_SLOT"
CDS_LIB"standard"
BODY_TYPE"PLUMBING"
HDL_TAP"TRUE";
"B \NAC \NWC"5;
"S \NAC"
BN"13"113;
%"TAP"
"6","(-3250,4700)","2","standard","I385";
;
ROOM"RISER1"
BOM_COST"IO_SLOT"
CDS_LIB"standard"
BODY_TYPE"PLUMBING"
HDL_TAP"TRUE";
"B \NAC \NWC"5;
"S \NAC"
BN"11"9;
%"TAP"
"6","(-3250,4600)","2","standard","I386";
;
ROOM"RISER1"
BOM_COST"IO_SLOT"
CDS_LIB"standard"
BODY_TYPE"PLUMBING"
HDL_TAP"TRUE";
"B \NAC \NWC"5;
"S \NAC"
BN"12"30;
%"TAP"
"6","(-3100,4450)","2","standard","I387";
;
ROOM"RISER1"
BOM_COST"IO_SLOT"
CDS_LIB"standard"
BODY_TYPE"PLUMBING"
HDL_TAP"TRUE";
"B \NAC \NWC"8;
"S \NAC"
BN"13"23;
%"TAP"
"6","(-3100,4250)","2","standard","I388";
;
ROOM"RISER1"
BOM_COST"IO_SLOT"
CDS_LIB"standard"
BODY_TYPE"PLUMBING"
HDL_TAP"TRUE";
"B \NAC \NWC"8;
"S \NAC"
BN"15"22;
%"TAP"
"6","(-3100,4350)","2","standard","I389";
;
ROOM"RISER1"
BOM_COST"IO_SLOT"
CDS_LIB"standard"
BODY_TYPE"PLUMBING"
HDL_TAP"TRUE";
"B \NAC \NWC"8;
"S \NAC"
BN"14"18;
%"TAP"
"6","(-3250,4400)","2","standard","I390";
;
ROOM"RISER1"
BOM_COST"IO_SLOT"
CDS_LIB"standard"
BODY_TYPE"PLUMBING"
HDL_TAP"TRUE";
"B \NAC \NWC"5;
"S \NAC"
BN"14"26;
%"TAP"
"6","(-3250,4300)","2","standard","I391";
;
ROOM"RISER1"
BOM_COST"IO_SLOT"
CDS_LIB"standard"
BODY_TYPE"PLUMBING"
HDL_TAP"TRUE";
"B \NAC \NWC"5;
"S \NAC"
BN"15"29;
END.
